(kicad_pcb
	(version 20260206)
	(generator "pcbnew")
	(generator_version "10.0")
	(general
		(thickness 1.6)
		(legacy_teardrops no)
	)
	(paper "A4")
	(title_block
		(title "peb — Lightning_PEB_BRD.brd")
		(comment 1 "Lightning (Wiwynn / Facebook NVMe JBOF) / footprints 1839-1845 of 2563")
	)
	(layers
		(0 "F.Cu" signal "TOP")
		(4 "In1.Cu" signal "L2GND")
		(6 "In2.Cu" signal "L3")
		(8 "In3.Cu" signal "L4VCC")
		(10 "In4.Cu" signal "L5VCC")
		(12 "In5.Cu" signal "L6")
		(14 "In6.Cu" signal "L7GND")
		(2 "B.Cu" signal "BOTTOM")
		(9 "F.Adhes" user "F.Adhesive")
		(11 "B.Adhes" user "B.Adhesive")
		(13 "F.Paste" user "Package Geometry/Pastemask Top")
		(15 "B.Paste" user "Package Geometry/Pastemask Bottom")
		(5 "F.SilkS" user "Ref Des/Silkscreen Top")
		(7 "B.SilkS" user "Ref Des/Silkscreen Bottom")
		(1 "F.Mask" user "Board Geometry/Soldermask Top")
		(3 "B.Mask" user "Board Geometry/Soldermask Bottom")
		(17 "Dwgs.User" user "User.Drawings")
		(19 "Cmts.User" user "User.Comments")
		(21 "Eco1.User" user "User.Eco1")
		(23 "Eco2.User" user "User.Eco2")
		(25 "Edge.Cuts" user "Board Geometry/Outline")
		(27 "Margin" user)
		(31 "F.CrtYd" user "Package Geometry/Place Bound Top")
		(29 "B.CrtYd" user "Package Geometry/Place Bound Bottom")
		(35 "F.Fab" user "Ref Des/Assembly Top")
		(33 "B.Fab" user "Ref Des/Assembly Bottom")
	)
	(footprint ""
		(layer "B.Cu")
		(at 162.941 -90.3224 -90)
		(property "Reference" "C721"
			(at 0 0 90)
			(layer "B.SilkS")
			(hide yes)
			(effects
				(font
					(size 1.27 1.27)
				)
				(justify mirror)
			)
		)
		(property "Value" "SCD1U10V2KX-5GP"
			(at -1.1811 -2.7051 270)
			(unlocked yes)
			(layer "B.Fab")
			(hide yes)
			(effects
				(font
					(size 1.016 1.016)
					(thickness 0.1524)
				)
				(justify mirror)
			)
		)
		(property "Device Type" "C402H22"
			(at -1.1811 -4.2291 270)
			(unlocked yes)
			(layer "B.Fab")
			(hide yes)
			(effects
				(font
					(size 1.016 1.016)
					(thickness 0.1524)
				)
				(justify mirror)
			)
		)
		(duplicate_pad_numbers_are_jumpers no)
		(fp_rect
			(start 0.4318 0.9525)
			(end -0.4318 -0.9525)
			(stroke
				(width 0)
				(type default)
			)
			(fill no)
			(layer "B.CrtYd")
		)
		(fp_rect
			(start 0.4318 0.9525)
			(end -0.4318 -0.9525)
			(stroke
				(width 0)
				(type default)
			)
			(fill no)
			(layer "B.Fab")
		)
		(pad "1" smd custom
			(at 0 -0.4445 90)
			(size 0.1524 0.1524)
			(layers "B.Cu" "B.Mask" "B.Paste")
			(net "P1V8_CLKGEN_A")
			(options
				(clearance outline)
				(anchor circle)
			)
			(primitives
				(gr_poly
					(pts
						(arc
							(start 0.3048 0.2032)
							(mid 0.275042 0.275042)
							(end 0.2032 0.3048)
						)
						(arc
							(start -0.2032 0.3048)
							(mid -0.275042 0.275042)
							(end -0.3048 0.2032)
						)
						(arc
							(start -0.3048 -0.2032)
							(mid -0.275042 -0.275042)
							(end -0.2032 -0.3048)
						)
						(arc
							(start 0.2032 -0.3048)
							(mid 0.275042 -0.275042)
							(end 0.3048 -0.2032)
						)
					)
					(width 0)
					(fill yes)
				)
			)
		)
		(pad "2" smd custom
			(at 0 0.4445 90)
			(size 0.1524 0.1524)
			(layers "B.Cu" "B.Mask" "B.Paste")
			(net "GND")
			(options
				(clearance outline)
				(anchor circle)
			)
			(primitives
				(gr_poly
					(pts
						(arc
							(start 0.3048 0.2032)
							(mid 0.275042 0.275042)
							(end 0.2032 0.3048)
						)
						(arc
							(start -0.2032 0.3048)
							(mid -0.275042 0.275042)
							(end -0.3048 0.2032)
						)
						(arc
							(start -0.3048 -0.2032)
							(mid -0.275042 -0.275042)
							(end -0.2032 -0.3048)
						)
						(arc
							(start 0.2032 -0.3048)
							(mid 0.275042 -0.275042)
							(end 0.3048 -0.2032)
						)
					)
					(width 0)
					(fill yes)
				)
			)
		)
	)
	(footprint ""
		(layer "B.Cu")
		(at 247.6373 -54.99354 -90)
		(property "Reference" "C594"
			(at 0 0 90)
			(layer "B.SilkS")
			(hide yes)
			(effects
				(font
					(size 1.27 1.27)
				)
				(justify mirror)
			)
		)
		(property "Value" "SCD1U16V1KX-1-GP"
			(at 2.8321 -1.7399 270)
			(unlocked yes)
			(layer "B.Fab")
			(hide yes)
			(effects
				(font
					(size 1.016 1.016)
					(thickness 0.1524)
				)
				(justify mirror)
			)
		)
		(property "Device Type" "C0201H13"
			(at 2.8321 -3.2639 270)
			(unlocked yes)
			(layer "B.Fab")
			(hide yes)
			(effects
				(font
					(size 1.016 1.016)
					(thickness 0.1524)
				)
				(justify mirror)
			)
		)
		(duplicate_pad_numbers_are_jumpers no)
		(fp_rect
			(start 0.2794 0.6477)
			(end -0.2794 -0.6477)
			(stroke
				(width 0)
				(type default)
			)
			(fill no)
			(layer "B.CrtYd")
		)
		(fp_rect
			(start 0.2794 0.6477)
			(end -0.2794 -0.6477)
			(stroke
				(width 0)
				(type default)
			)
			(fill no)
			(layer "B.Fab")
		)
		(pad "1" smd custom
			(at 0 -0.2794 90)
			(size 0.0762 0.0762)
			(layers "B.Cu" "B.Mask" "B.Paste")
			(net "DUT_AVD_PCIE")
			(options
				(clearance outline)
				(anchor circle)
			)
			(primitives
				(gr_poly
					(pts
						(arc
							(start 0.1524 0.127)
							(mid 0.137521 0.162921)
							(end 0.1016 0.1778)
						)
						(arc
							(start -0.1016 0.1778)
							(mid -0.137521 0.162921)
							(end -0.1524 0.127)
						)
						(arc
							(start -0.1524 -0.127)
							(mid -0.137521 -0.162921)
							(end -0.1016 -0.1778)
						)
						(arc
							(start 0.1016 -0.1778)
							(mid 0.137521 -0.162921)
							(end 0.1524 -0.127)
						)
					)
					(width 0)
					(fill yes)
				)
			)
		)
		(pad "2" smd custom
			(at 0 0.2794 90)
			(size 0.0762 0.0762)
			(layers "B.Cu" "B.Mask" "B.Paste")
			(net "GND")
			(options
				(clearance outline)
				(anchor circle)
			)
			(primitives
				(gr_poly
					(pts
						(arc
							(start 0.1524 0.127)
							(mid 0.137521 0.162921)
							(end 0.1016 0.1778)
						)
						(arc
							(start -0.1016 0.1778)
							(mid -0.137521 0.162921)
							(end -0.1524 0.127)
						)
						(arc
							(start -0.1524 -0.127)
							(mid -0.137521 -0.162921)
							(end -0.1016 -0.1778)
						)
						(arc
							(start 0.1016 -0.1778)
							(mid 0.137521 -0.162921)
							(end 0.1524 -0.127)
						)
					)
					(width 0)
					(fill yes)
				)
			)
		)
	)
	(footprint ""
		(layer "B.Cu")
		(at 38.1381 -114.55146 180)
		(property "Reference" "R442"
			(at 0 0 0)
			(layer "B.SilkS")
			(hide yes)
			(effects
				(font
					(size 1.27 1.27)
				)
				(justify mirror)
			)
		)
		(property "Value" "0R2J-2-GP"
			(at -0.064008 -3.993896 180)
			(unlocked yes)
			(layer "B.Fab")
			(hide yes)
			(effects
				(font
					(size 1.016 1.016)
					(thickness 0.1524)
				)
				(justify mirror)
			)
		)
		(property "Device Type" "R402H16"
			(at -0.064008 -5.517896 180)
			(unlocked yes)
			(layer "B.Fab")
			(hide yes)
			(effects
				(font
					(size 1.016 1.016)
					(thickness 0.1524)
				)
				(justify mirror)
			)
		)
		(duplicate_pad_numbers_are_jumpers no)
		(fp_line
			(start 0.508 -0.9398)
			(end 0.508 0.9398)
			(stroke
				(width 0.1524)
				(type default)
			)
			(layer "B.SilkS")
		)
		(fp_line
			(start -0.508 -0.9398)
			(end 0.508 -0.9398)
			(stroke
				(width 0.1524)
				(type default)
			)
			(layer "B.SilkS")
		)
		(fp_rect
			(start 0.508 0.9398)
			(end -0.508 -0.9398)
			(stroke
				(width 0)
				(type default)
			)
			(fill no)
			(layer "B.CrtYd")
		)
		(fp_rect
			(start 0.508 0.9398)
			(end -0.508 -0.9398)
			(stroke
				(width 0)
				(type default)
			)
			(fill no)
			(layer "B.Fab")
		)
		(pad "1" smd custom
			(at 0 -0.4445)
			(size 0.1397 0.1397)
			(layers "B.Cu" "B.Mask" "B.Paste")
			(net "GND")
			(options
				(clearance outline)
				(anchor circle)
			)
			(primitives
				(gr_poly
					(pts
						(arc
							(start -0.1778 0.2794)
							(mid -0.249642 0.249642)
							(end -0.2794 0.1778)
						)
						(arc
							(start -0.2794 -0.1778)
							(mid -0.249642 -0.249642)
							(end -0.1778 -0.2794)
						)
						(arc
							(start 0.1778 -0.2794)
							(mid 0.249642 -0.249642)
							(end 0.2794 -0.1778)
						)
						(arc
							(start 0.2794 0.1778)
							(mid 0.249642 0.249642)
							(end 0.1778 0.2794)
						)
					)
					(width 0)
					(fill yes)
				)
			)
		)
		(pad "2" smd custom
			(at 0 0.4445)
			(size 0.1397 0.1397)
			(layers "B.Cu" "B.Mask" "B.Paste")
			(net "RMII_PHY_BMC_RXD0")
			(options
				(clearance outline)
				(anchor circle)
			)
			(primitives
				(gr_poly
					(pts
						(arc
							(start -0.1778 0.2794)
							(mid -0.249642 0.249642)
							(end -0.2794 0.1778)
						)
						(arc
							(start -0.2794 -0.1778)
							(mid -0.249642 -0.249642)
							(end -0.1778 -0.2794)
						)
						(arc
							(start 0.1778 -0.2794)
							(mid 0.249642 -0.249642)
							(end 0.2794 -0.1778)
						)
						(arc
							(start 0.2794 0.1778)
							(mid 0.249642 0.249642)
							(end 0.1778 0.2794)
						)
					)
					(width 0)
					(fill yes)
				)
			)
		)
	)
	(footprint ""
		(layer "B.Cu")
		(at 59.218322 -120.352566 90)
		(property "Reference" "R472"
			(at 0 0 90)
			(layer "B.SilkS")
			(hide yes)
			(effects
				(font
					(size 1.27 1.27)
				)
				(justify mirror)
			)
		)
		(property "Value" "2K2R2J-2-GP"
			(at -0.064008 -3.993896 90)
			(unlocked yes)
			(layer "B.Fab")
			(hide yes)
			(effects
				(font
					(size 1.016 1.016)
					(thickness 0.1524)
				)
				(justify mirror)
			)
		)
		(property "Device Type" "R402H16"
			(at -0.064008 -5.517896 90)
			(unlocked yes)
			(layer "B.Fab")
			(hide yes)
			(effects
				(font
					(size 1.016 1.016)
					(thickness 0.1524)
				)
				(justify mirror)
			)
		)
		(duplicate_pad_numbers_are_jumpers no)
		(fp_line
			(start 0.508 -0.9398)
			(end 0.508 0.9398)
			(stroke
				(width 0.1524)
				(type default)
			)
			(layer "B.SilkS")
		)
		(fp_line
			(start -0.508 -0.9398)
			(end 0.508 -0.9398)
			(stroke
				(width 0.1524)
				(type default)
			)
			(layer "B.SilkS")
		)
		(fp_rect
			(start 0.508 0.9398)
			(end -0.508 -0.9398)
			(stroke
				(width 0)
				(type default)
			)
			(fill no)
			(layer "B.CrtYd")
		)
		(fp_rect
			(start 0.508 0.9398)
			(end -0.508 -0.9398)
			(stroke
				(width 0)
				(type default)
			)
			(fill no)
			(layer "B.Fab")
		)
		(pad "1" smd custom
			(at 0 -0.4445 270)
			(size 0.1397 0.1397)
			(layers "B.Cu" "B.Mask" "B.Paste")
			(net "BMC_I2C5_D_PEB_DEVICE_SDA")
			(options
				(clearance outline)
				(anchor circle)
			)
			(primitives
				(gr_poly
					(pts
						(arc
							(start -0.1778 0.2794)
							(mid -0.249642 0.249642)
							(end -0.2794 0.1778)
						)
						(arc
							(start -0.2794 -0.1778)
							(mid -0.249642 -0.249642)
							(end -0.1778 -0.2794)
						)
						(arc
							(start 0.1778 -0.2794)
							(mid 0.249642 -0.249642)
							(end 0.2794 -0.1778)
						)
						(arc
							(start 0.2794 0.1778)
							(mid 0.249642 0.249642)
							(end 0.1778 0.2794)
						)
					)
					(width 0)
					(fill yes)
				)
			)
		)
		(pad "2" smd custom
			(at 0 0.4445 270)
			(size 0.1397 0.1397)
			(layers "B.Cu" "B.Mask" "B.Paste")
			(net "P3V3_STBY")
			(options
				(clearance outline)
				(anchor circle)
			)
			(primitives
				(gr_poly
					(pts
						(arc
							(start -0.1778 0.2794)
							(mid -0.249642 0.249642)
							(end -0.2794 0.1778)
						)
						(arc
							(start -0.2794 -0.1778)
							(mid -0.249642 -0.249642)
							(end -0.1778 -0.2794)
						)
						(arc
							(start 0.1778 -0.2794)
							(mid 0.249642 -0.249642)
							(end 0.2794 -0.1778)
						)
						(arc
							(start 0.2794 0.1778)
							(mid 0.249642 0.249642)
							(end 0.1778 0.2794)
						)
					)
					(width 0)
					(fill yes)
				)
			)
		)
	)
	(footprint ""
		(layer "B.Cu")
		(at 134.342124 -208.889092 180)
		(property "Reference" "R4118"
			(at 0 0 0)
			(layer "B.SilkS")
			(hide yes)
			(effects
				(font
					(size 1.27 1.27)
				)
				(justify mirror)
			)
		)
		(property "Value" "4K7R2F-GP"
			(at -0.064008 -3.993896 180)
			(unlocked yes)
			(layer "B.Fab")
			(hide yes)
			(effects
				(font
					(size 1.016 1.016)
					(thickness 0.1524)
				)
				(justify mirror)
			)
		)
		(property "Device Type" "R402H16"
			(at -0.064008 -5.517896 180)
			(unlocked yes)
			(layer "B.Fab")
			(hide yes)
			(effects
				(font
					(size 1.016 1.016)
					(thickness 0.1524)
				)
				(justify mirror)
			)
		)
		(duplicate_pad_numbers_are_jumpers no)
		(fp_line
			(start 0.508 -0.9398)
			(end 0.508 0.9398)
			(stroke
				(width 0.1524)
				(type default)
			)
			(layer "B.SilkS")
		)
		(fp_line
			(start -0.508 -0.9398)
			(end 0.508 -0.9398)
			(stroke
				(width 0.1524)
				(type default)
			)
			(layer "B.SilkS")
		)
		(fp_rect
			(start 0.508 0.9398)
			(end -0.508 -0.9398)
			(stroke
				(width 0)
				(type default)
			)
			(fill no)
			(layer "B.CrtYd")
		)
		(fp_rect
			(start 0.508 0.9398)
			(end -0.508 -0.9398)
			(stroke
				(width 0)
				(type default)
			)
			(fill no)
			(layer "B.Fab")
		)
		(pad "1" smd custom
			(at 0 -0.4445)
			(size 0.1397 0.1397)
			(layers "B.Cu" "B.Mask" "B.Paste")
			(net "SSD_PRSNT#6")
			(options
				(clearance outline)
				(anchor circle)
			)
			(primitives
				(gr_poly
					(pts
						(arc
							(start -0.1778 0.2794)
							(mid -0.249642 0.249642)
							(end -0.2794 0.1778)
						)
						(arc
							(start -0.2794 -0.1778)
							(mid -0.249642 -0.249642)
							(end -0.1778 -0.2794)
						)
						(arc
							(start 0.1778 -0.2794)
							(mid 0.249642 -0.249642)
							(end 0.2794 -0.1778)
						)
						(arc
							(start 0.2794 0.1778)
							(mid 0.249642 0.249642)
							(end 0.1778 0.2794)
						)
					)
					(width 0)
					(fill yes)
				)
			)
		)
		(pad "2" smd custom
			(at 0 0.4445)
			(size 0.1397 0.1397)
			(layers "B.Cu" "B.Mask" "B.Paste")
			(net "P3V3_STBY")
			(options
				(clearance outline)
				(anchor circle)
			)
			(primitives
				(gr_poly
					(pts
						(arc
							(start -0.1778 0.2794)
							(mid -0.249642 0.249642)
							(end -0.2794 0.1778)
						)
						(arc
							(start -0.2794 -0.1778)
							(mid -0.249642 -0.249642)
							(end -0.1778 -0.2794)
						)
						(arc
							(start 0.1778 -0.2794)
							(mid 0.249642 -0.249642)
							(end 0.2794 -0.1778)
						)
						(arc
							(start 0.2794 0.1778)
							(mid 0.249642 0.249642)
							(end 0.1778 0.2794)
						)
					)
					(width 0)
					(fill yes)
				)
			)
		)
	)
	(footprint ""
		(layer "B.Cu")
		(at 78.843124 -183.235092)
		(property "Reference" "R4108"
			(at 0 0 0)
			(layer "B.SilkS")
			(hide yes)
			(effects
				(font
					(size 1.27 1.27)
				)
				(justify mirror)
			)
		)
		(property "Value" "4K7R2F-GP"
			(at -0.064008 -3.993896 0)
			(unlocked yes)
			(layer "B.Fab")
			(hide yes)
			(effects
				(font
					(size 1.016 1.016)
					(thickness 0.1524)
				)
				(justify mirror)
			)
		)
		(property "Device Type" "R402H16"
			(at -0.064008 -5.517896 0)
			(unlocked yes)
			(layer "B.Fab")
			(hide yes)
			(effects
				(font
					(size 1.016 1.016)
					(thickness 0.1524)
				)
				(justify mirror)
			)
		)
		(duplicate_pad_numbers_are_jumpers no)
		(fp_line
			(start -0.508 -0.9398)
			(end 0.508 -0.9398)
			(stroke
				(width 0.1524)
				(type default)
			)
			(layer "B.SilkS")
		)
		(fp_line
			(start 0.508 -0.9398)
			(end 0.508 0.9398)
			(stroke
				(width 0.1524)
				(type default)
			)
			(layer "B.SilkS")
		)
		(fp_rect
			(start 0.508 0.9398)
			(end -0.508 -0.9398)
			(stroke
				(width 0)
				(type default)
			)
			(fill no)
			(layer "B.CrtYd")
		)
		(fp_rect
			(start 0.508 0.9398)
			(end -0.508 -0.9398)
			(stroke
				(width 0)
				(type default)
			)
			(fill no)
			(layer "B.Fab")
		)
		(pad "1" smd custom
			(at 0 -0.4445 180)
			(size 0.1397 0.1397)
			(layers "B.Cu" "B.Mask" "B.Paste")
			(net "SSD_PERST#5")
			(options
				(clearance outline)
				(anchor circle)
			)
			(primitives
				(gr_poly
					(pts
						(arc
							(start -0.1778 0.2794)
							(mid -0.249642 0.249642)
							(end -0.2794 0.1778)
						)
						(arc
							(start -0.2794 -0.1778)
							(mid -0.249642 -0.249642)
							(end -0.1778 -0.2794)
						)
						(arc
							(start 0.1778 -0.2794)
							(mid 0.249642 -0.249642)
							(end 0.2794 -0.1778)
						)
						(arc
							(start 0.2794 0.1778)
							(mid 0.249642 0.249642)
							(end 0.1778 0.2794)
						)
					)
					(width 0)
					(fill yes)
				)
			)
		)
		(pad "2" smd custom
			(at 0 0.4445 180)
			(size 0.1397 0.1397)
			(layers "B.Cu" "B.Mask" "B.Paste")
			(net "P3V3_STBY")
			(options
				(clearance outline)
				(anchor circle)
			)
			(primitives
				(gr_poly
					(pts
						(arc
							(start -0.1778 0.2794)
							(mid -0.249642 0.249642)
							(end -0.2794 0.1778)
						)
						(arc
							(start -0.2794 -0.1778)
							(mid -0.249642 -0.249642)
							(end -0.1778 -0.2794)
						)
						(arc
							(start 0.1778 -0.2794)
							(mid 0.249642 -0.249642)
							(end 0.2794 -0.1778)
						)
						(arc
							(start 0.2794 0.1778)
							(mid 0.249642 0.249642)
							(end 0.1778 0.2794)
						)
					)
					(width 0)
					(fill yes)
				)
			)
		)
	)
	(footprint ""
		(layer "B.Cu")
		(at 77.343 -198.1454 90)
		(property "Reference" "C4112"
			(at 0 0 90)
			(layer "B.SilkS")
			(hide yes)
			(effects
				(font
					(size 1.27 1.27)
				)
				(justify mirror)
			)
		)
		(property "Value" "SCD1U25V3KX-GP"
			(at 0 -2.8194 90)
			(unlocked yes)
			(layer "B.Fab")
			(hide yes)
			(effects
				(font
					(size 1.016 1.016)
					(thickness 0.1524)
				)
				(justify mirror)
			)
		)
		(property "Device Type" "C603H36"
			(at 0 -4.3434 90)
			(unlocked yes)
			(layer "B.Fab")
			(hide yes)
			(effects
				(font
					(size 1.016 1.016)
					(thickness 0.1524)
				)
				(justify mirror)
			)
		)
		(duplicate_pad_numbers_are_jumpers no)
		(fp_line
			(start -0.508 0)
			(end 0.508 0)
			(stroke
				(width 0.2032)
				(type default)
			)
			(layer "B.SilkS")
		)
		(fp_rect
			(start 0.5842 1.3335)
			(end -0.5842 -1.3335)
			(stroke
				(width 0)
				(type default)
			)
			(fill no)
			(layer "B.CrtYd")
		)
		(fp_rect
			(start 0.5842 1.3335)
			(end -0.5842 -1.3335)
			(stroke
				(width 0)
				(type default)
			)
			(fill no)
			(layer "B.Fab")
		)
		(pad "1" smd custom
			(at 0 -0.762 270)
			(size 0.2159 0.2159)
			(layers "B.Cu" "B.Mask" "B.Paste")
			(net "GND")
			(options
				(clearance outline)
				(anchor circle)
			)
			(primitives
				(gr_poly
					(pts
						(arc
							(start -0.3302 0.4318)
							(mid -0.402042 0.402042)
							(end -0.4318 0.3302)
						)
						(arc
							(start -0.4318 -0.3302)
							(mid -0.402042 -0.402042)
							(end -0.3302 -0.4318)
						)
						(arc
							(start 0.3302 -0.4318)
							(mid 0.402042 -0.402042)
							(end 0.4318 -0.3302)
						)
						(arc
							(start 0.4318 0.3302)
							(mid 0.402042 0.402042)
							(end 0.3302 0.4318)
						)
					)
					(width 0)
					(fill yes)
				)
			)
		)
		(pad "2" smd custom
			(at 0 0.762 270)
			(size 0.2159 0.2159)
			(layers "B.Cu" "B.Mask" "B.Paste")
			(net "SSD_PWREN10_R")
			(options
				(clearance outline)
				(anchor circle)
			)
			(primitives
				(gr_poly
					(pts
						(arc
							(start -0.3302 0.4318)
							(mid -0.402042 0.402042)
							(end -0.4318 0.3302)
						)
						(arc
							(start -0.4318 -0.3302)
							(mid -0.402042 -0.402042)
							(end -0.3302 -0.4318)
						)
						(arc
							(start 0.3302 -0.4318)
							(mid 0.402042 -0.402042)
							(end 0.4318 -0.3302)
						)
						(arc
							(start 0.4318 0.3302)
							(mid 0.402042 0.402042)
							(end 0.3302 0.4318)
						)
					)
					(width 0)
					(fill yes)
				)
			)
		)
	)
)
